G04 ================== begin FILE IDENTIFICATION RECORD ==================*
G04 Layout Name:  9324_DA0F0TMBIJ0_F0T_Motherboard_J_v01_20230324_0910.brd*
G04 Film Name:    outline*
G04 File Format:  Gerber RS274X*
G04 File Origin:  Cadence Allegro 17.2-S081*
G04 Origin Date:  Sat Mar 25 08:45:16 2023*
G04 *
G04 Layer:  BOARD GEOMETRY/DESIGN_OUTLINE*
G04 Layer:  BOARD GEOMETRY/CUTOUT*
G04 *
G04 Offset:    (0.00 0.00)*
G04 Mirror:    No*
G04 Mode:      Positive*
G04 Rotation:  0*
G04 FullContactRelief:  No*
G04 UndefLineWidth:     6.00*
G04 ================== end FILE IDENTIFICATION RECORD ====================*
%FSLAX25Y25*MOIN*%
%IR0*IPPOS*OFA0.00000B0.00000*MIA0B0*SFA1.00000B1.00000*%
%ADD10C,.006*%
G75*
%LPD*%
G75*
G54D10*
G01X51583Y1969D02*
G03X53551Y0I1968J-1D01*
G01X319693D01*
G03X321661Y1969I0J1968D01*
G01Y38504D01*
G02X329535Y46378I7874J0D01*
G01X488591D01*
G02X496465Y38504I0J-7874D01*
G01Y22756D01*
G03X498433Y20787I1968J-1D01*
G01X764575D01*
G03X766543Y22756I0J1968D01*
G01Y38504D01*
G02X774417Y46378I7874J0D01*
G01X871260D01*
G03X879134Y54252I0J7874D01*
G01Y131004D01*
G02X887008Y138878I7874J0D01*
G01X1011024D01*
G02X1018898Y131004I0J-7874D01*
G01Y54252D01*
G03X1026772Y46378I7874J0D01*
G01X1518118D01*
G02X1525992Y38504I0J-7874D01*
G01Y1969D01*
G03X1527961Y0I1969J0D01*
G01X1794102D01*
G03X1796071Y1969I0J1969D01*
G01Y38504D01*
G02X1803945Y46378I7874J0D01*
G01X1849606D01*
G03X1857480Y54252I0J7874D01*
G01Y305794D01*
G03X1855174Y311361I-7873J0D01*
G01X1846007Y320528D01*
G02X1843701Y326096I5568J5568D01*
G01Y1593983D01*
G03X1841395Y1599550I-7873J0D01*
G01X1834196Y1606749D01*
G02X1831890Y1612317I5568J5568D01*
G01Y1732244D01*
G03X1824016Y1740118I-7874J0D01*
G01X1091777D01*
G03X1089809Y1738150I0J-1968D01*
G01Y1736654D01*
G02X1087854Y1734921I-1955J236D01*
G01X769705D01*
G02X767750Y1736654I0J1969D01*
G01Y1738150D01*
G03X765782Y1740118I-1968J0D01*
G01X33465D01*
G03X25591Y1732244I0J-7874D01*
G01Y1612317D01*
G02X23284Y1606749I-7875J1D01*
G01X10180Y1593645D01*
G03X7874Y1588077I5568J-5568D01*
G01Y320191D01*
G02X5568Y314623I-7874J0D01*
G01X2306Y311361D01*
G03X0Y305794I5567J-5567D01*
G01Y54252D01*
G03X7874Y46378I7874J0D01*
G01X43709D01*
G02X51583Y38504I0J-7874D01*
G01Y1969D01*
G01X16535Y87795D02*
G02X38583I11024J0D01*
G02X16535I-11024J0D01*
G01X18661Y1420331D02*
G02X58031I19685J0D01*
G02X18661I-19685J0D01*
G01X29685Y631890D02*
G02X51732I11023J0D01*
G02X29685I-11024J0D01*
G01Y1368898D02*
G02X51732I11023J0D01*
G02X29685I-11024J0D01*
G01X62205Y1714961D02*
G02X40157I-11024J0D01*
G02X62205I11024J0D01*
G01X52141Y119148D02*
X56741Y123451D01*
G02X65079Y114538I4169J-4456D01*
G01X60479Y110235D01*
G02X52141Y119148I-4169J4456D01*
G01X98248Y605378D02*
G02X137618I19685J0D01*
G02X98248I-19685J0D01*
G01X197098Y294335D02*
Y260083D01*
G02X157728I-19685J0D01*
G01Y294335D01*
G02X197098I19685J0D01*
G01X196996Y1671142D02*
Y1644764D01*
G02X157626I-19685J0D01*
G01Y1671142D01*
G02X196996I19685J0D01*
G01X247177Y191535D02*
X253476D01*
G02Y178937I0J-6299D01*
G01X247177D01*
G02Y191535I0J6299D01*
G01X269618Y185236D02*
G02X284579I7481J0D01*
G02X269618I-7481J0D01*
G01X300019Y991220D02*
G02X313523I6752J0D01*
G02X300019I-6752J0D01*
G01X316200Y1391831D02*
G02X328799I6299J0D01*
G02X316200I-6299J0D01*
G01X343346Y811122D02*
G02X356850I6752J0D01*
G02X343346I-6752J0D01*
G01X349310Y1171319D02*
G02X362814I6752J0D01*
G02X349310I-6752J0D01*
G01X362598Y87795D02*
G02X384646I11024J0D01*
G02X362598I-11024J0D01*
G01X365287Y191535D02*
X371587D01*
G02Y178937I0J-6299D01*
G01X365287D01*
G02Y191535I0J6299D01*
G01X384647Y1714961D02*
G02X406694I11023J0D01*
G02X384647I-11023J0D01*
G01X387728Y185236D02*
G02X402689I7481J0D01*
G02X387728I-7480J0D01*
G01X447283Y1698268D02*
G02X434803I-6240J0D01*
G02X447283I6240J0D01*
G01X524488Y811122D02*
G02X537992I6752J0D01*
G02X524488I-6752J0D01*
G01X518523Y1171319D02*
G02X532027I6752J0D01*
G02X518523I-6752J0D01*
G01X531177Y1395413D02*
G02X543775I6299J0D01*
G02X531177I-6299J0D01*
G01X567814Y991220D02*
G02X581318I6752J0D01*
G02X567814I-6752J0D01*
G01X650000Y631890D02*
G02X672047I11023J0D01*
G02X650000I-11024J0D01*
G01X723870Y294362D02*
Y260110D01*
G02X684500I-19685J0D01*
G01Y294362D01*
G02X723870I19685J0D01*
G01X696654Y1714961D02*
G02X718701I11023J0D01*
G02X696654I-11024J0D01*
G01X743917Y605413D02*
G02X783287I19685J0D01*
G02X743917I-19685J0D01*
G01X789764Y87795D02*
G02X811811I11023J0D01*
G02X789764I-11023J0D01*
G01X794864Y204724D02*
G02X816517I10827J0D01*
G02X794864I-10826J0D01*
G01X833366Y1420331D02*
G02X849114I7874J0D01*
G02X833366I-7874J0D01*
G01X896260Y175197D02*
G02X904134I3937J0D01*
G02X896260I-3937J0D01*
G01X936673Y311614D02*
X920807D01*
G02X936673I7933J10039D01*
G01X920669Y757874D02*
G02X942717I11024J0D01*
G02X920669I-11024J0D01*
G01Y1072835D02*
G02X942717I11024J0D01*
G02X920669I-11024J0D01*
G01Y1387795D02*
G02X942717I11024J0D01*
G02X920669I-11024J0D01*
G01X940748Y155217D02*
G02X948622I3937J0D01*
G02X940748I-3937J0D01*
G01X1008366Y1420331D02*
G02X1024114I7874J0D01*
G02X1008366I-7874J0D01*
G01X1034843Y87795D02*
G02X1056890I11024J0D01*
G02X1034843I-11023J0D01*
G01X1046832Y204724D02*
G02X1068486I10827J0D01*
G02X1046832I-10827J0D01*
G01X1074390Y605378D02*
G02X1113760I19685J0D01*
G02X1074390I-19685J0D01*
G01X1173240Y294335D02*
Y260083D01*
G02X1133870I-19685J0D01*
G01Y294335D01*
G02X1173240I19685J0D01*
G01X1125512Y1653543D02*
G02X1142047I8267J0D01*
G02X1125512I-8268J0D01*
G01X1144685Y1714961D02*
G02X1166732I11023J0D01*
G02X1144685I-11024J0D01*
G01X1241535Y269488D02*
G02X1253740I6103J0D01*
G02X1241535I-6102J0D01*
G01X1260236Y631890D02*
G02X1282283I11023J0D01*
G02X1260236I-11023J0D01*
G01X1276161Y991220D02*
G02X1289665I6752J0D01*
G02X1276161I-6752J0D01*
G01X1292342Y1391831D02*
G02X1304940I6299J0D01*
G02X1292342I-6299J0D01*
G01X1319488Y811122D02*
G02X1332992I6752J0D01*
G02X1319488I-6752J0D01*
G01X1325452Y1171319D02*
G02X1338956I6752J0D01*
G02X1325452I-6752J0D01*
G01X1399016Y112008D02*
G02X1411220I6102J0D01*
G02X1399016I-6102J0D01*
G01X1422677Y1698268D02*
G02X1410197I-6240J0D01*
G02X1422677I6240J0D01*
G01X1450782Y1714961D02*
G02X1472829I11023J0D01*
G02X1450782I-11024J0D01*
G01X1488583Y87795D02*
G02X1510630I11024J0D01*
G02X1488583I-11023J0D01*
G01X1500629Y811122D02*
G02X1514133I6752J0D01*
G02X1500629I-6752J0D01*
G01X1494665Y1171319D02*
G02X1508169I6752J0D01*
G02X1494665I-6752J0D01*
G01X1507318Y1395413D02*
G02X1519917I6299J0D01*
G02X1507318I-6300J0D01*
G01X1543956Y991220D02*
G02X1557460I6752J0D01*
G02X1543956I-6752J0D01*
G01X1700012Y294362D02*
Y260110D01*
G02X1660642I-19685J0D01*
G01Y294362D01*
G02X1700012I19685J0D01*
G01X1660547Y1644764D02*
Y1671142D01*
G02X1699917I19685J0D01*
G01Y1644764D01*
G02X1660547I-19685J0D01*
G01X1720059Y605413D02*
G02X1759429I19685J0D01*
G02X1720059I-19685J0D01*
G01X1760827Y1714961D02*
G02X1773031I6102J0D01*
G02X1760827I-6102J0D01*
G01X1799528Y1420331D02*
G02X1838898I19685J0D01*
G02X1799528I-19685J0D01*
G01X1795276Y1714961D02*
G02X1817323I11024J0D01*
G02X1795276I-11023J0D01*
G01X1805748Y631890D02*
G02X1827795I11024J0D01*
G02X1805748I-11023J0D01*
G01Y1368898D02*
G02X1827795I11024J0D01*
G02X1805748I-11023J0D01*
G01X1818898Y87795D02*
G02X1840945I11023J0D01*
G02X1818898I-11023J0D01*
G01X1835827Y133465D02*
Y127165D01*
G02X1823622I-6103J0D01*
G01Y133465D01*
G02X1835827I6102J0D01*
M02*
